# SCM (Grand Teton) — schematic netlist excerpt (pin names and nets, part order shuffled) for the footprints in the layout excerpt that follows; sources: Cadence DE-HDL packaged netlist, KiCad conversion of 12092022_DA0F0TMDCD0_F0T_Management_Board_D_brd_V3_OCP.brd

J22  PICOPROBE_BXA  DELTA-L 4.0 EMPTY  pkg TRIANG_LAUNCH_3PXB  page 58
  \1_p\  = 85_10INCH_TOP_DP
  \2_n\  = 85_10INCH_TOP_DN
  \3_g\  = GND_P1

(kicad_pcb
	(version 20260206)
	(generator "pcbnew")
	(generator_version "10.0")
	(general
		(thickness 1.6)
		(legacy_teardrops no)
	)
	(paper "A4")
	(title_block
		(title "12092022_DA0F0TMDCD0_F0T_Management_Board_D_brd_V3_OCP.brd")
		(comment 1 "Grand Teton / footprints 157-157 of 1440")
	)
	(layers
		(0 "F.Cu" signal "TOP")
		(4 "In1.Cu" signal "GND")
		(6 "In2.Cu" signal "IN1")
		(8 "In3.Cu" signal "GND1")
		(10 "In4.Cu" signal "IN2")
		(12 "In5.Cu" signal "VCC")
		(14 "In6.Cu" signal "VCC1")
		(16 "In7.Cu" signal "IN3")
		(18 "In8.Cu" signal "GND2")
		(20 "In9.Cu" signal "IN4")
		(22 "In10.Cu" signal "GND3")
		(2 "B.Cu" signal "BOTTOM")
		(9 "F.Adhes" user "F.Adhesive")
		(11 "B.Adhes" user "B.Adhesive")
		(13 "F.Paste" user "Package Geometry/Pastemask Top")
		(15 "B.Paste" user "Package Geometry/Pastemask Bottom")
		(5 "F.SilkS" user "Ref Des/Silkscreen Top")
		(7 "B.SilkS" user "Ref Des/Silkscreen Bottom")
		(1 "F.Mask" user "Board Geometry/Soldermask Top")
		(3 "B.Mask" user "Board Geometry/Soldermask Bottom")
		(17 "Dwgs.User" user "User.Drawings")
		(19 "Cmts.User" user "User.Comments")
		(21 "Eco1.User" user "User.Eco1")
		(23 "Eco2.User" user "User.Eco2")
		(25 "Edge.Cuts" user "Board Geometry/Outline")
		(27 "Margin" user)
		(31 "F.CrtYd" user "Package Geometry/Place Bound Top")
		(29 "B.CrtYd" user "Package Geometry/Place Bound Bottom")
		(35 "F.Fab" user "Ref Des/Assembly Top")
		(33 "B.Fab" user "Ref Des/Assembly Bottom")
	)
	(footprint ""
		(layer "F.Cu")
		(at 103.8225 -54.403752 -90)
		(property "Reference" "J22"
			(at -4.016248 -1.48717 90)
			(unlocked yes)
			(layer "F.SilkS")
			(effects
				(font
					(size 0.7874 0.5842)
					(thickness 0.1524)
				)
				(justify left)
			)
		)
		(property "Value" ""
			(at 0 0 270)
			(layer "F.Fab")
			(effects
				(font
					(size 1.27 1.27)
				)
			)
		)
		(duplicate_pad_numbers_are_jumpers no)
		(fp_line
			(start -1.2192 2.1082)
			(end -1.2192 -2.1082)
			(stroke
				(width 0.1524)
				(type default)
			)
			(layer "F.SilkS")
		)
		(fp_line
			(start 1.2192 2.1082)
			(end -1.2192 2.1082)
			(stroke
				(width 0.1524)
				(type default)
			)
			(layer "F.SilkS")
		)
		(fp_line
			(start 1.2192 0.456692)
			(end 1.2192 2.1082)
			(stroke
				(width 0.1524)
				(type default)
			)
			(layer "F.SilkS")
		)
		(fp_line
			(start -1.2192 -2.1082)
			(end 1.2192 -2.1082)
			(stroke
				(width 0.1524)
				(type default)
			)
			(layer "F.SilkS")
		)
		(fp_line
			(start 1.2192 -2.1082)
			(end 1.2192 -0.450596)
			(stroke
				(width 0.1524)
				(type default)
			)
			(layer "F.SilkS")
		)
		(pad "" np_thru_hole circle
			(at -2.8829 -1.27 180)
			(size 1.0414 1.0414)
			(drill 1.0414)
			(layers "*.Cu" "*.Mask")
			(clearance 0.381)
			(thermal_gap 0.381)
		)
		(pad "" np_thru_hole circle
			(at -2.8829 1.27 180)
			(size 1.0414 1.0414)
			(drill 1.0414)
			(layers "*.Cu" "*.Mask")
			(clearance 0.381)
			(thermal_gap 0.381)
		)
		(pad "" np_thru_hole circle
			(at 3.4671 -1.27 180)
			(size 1.0414 1.0414)
			(drill 1.0414)
			(layers "*.Cu" "*.Mask")
			(clearance 0.381)
			(thermal_gap 0.381)
		)
		(pad "" np_thru_hole circle
			(at 3.4671 1.27 180)
			(size 1.0414 1.0414)
			(drill 1.0414)
			(layers "*.Cu" "*.Mask")
			(clearance 0.381)
			(thermal_gap 0.381)
		)
		(pad "1" smd rect
			(at 0.8255 -0.249936 180)
			(size 0.3048 0.508)
			(layers "F.Cu" "F.Mask" "F.Paste")
			(net "85_10INCH_TOP_DP")
		)
		(pad "2" smd rect
			(at 0.8255 0.249936 180)
			(size 0.3048 0.508)
			(layers "F.Cu" "F.Mask" "F.Paste")
			(net "85_10INCH_TOP_DN")
		)
		(pad "3" smd circle
			(at 0 0 270)
			(size 0 0)
			(layers "F.Cu" "F.Mask" "F.Paste")
			(net "GND_P1")
		)
		(zone
			(layer "F.Cu")
			(hatch none 0.5)
			(connect_pads
				(clearance 0)
			)
			(min_thickness 0.25)
			(keepout
				(tracks not_allowed)
				(vias allowed)
				(pads allowed)
				(copperpour not_allowed)
				(footprints allowed)
			)
			(placement
				(enabled no)
				(sheetname "")
			)
			(fill
				(thermal_gap 0.5)
				(thermal_bridge_width 0.5)
				(island_removal_mode 0)
			)
			(polygon
				(pts
					(xy 104.37114 -53.286152) (xy 104.275636 -53.286152) (xy 104.275636 -53.883052) (xy 103.869236 -53.883052)
					(xy 103.869236 -53.286152) (xy 103.775764 -53.286152) (xy 103.775764 -53.883052) (xy 103.369364 -53.883052)
					(xy 103.369364 -53.286152) (xy 103.27386 -53.286152) (xy 103.27386 -53.984652) (xy 104.37114 -53.984652)
				)
			)
		)
		(zone
			(layers "F.Cu" "B.Cu" "In1.Cu" "In2.Cu" "In3.Cu" "In4.Cu" "In5.Cu" "In6.Cu"
				"In7.Cu" "In8.Cu" "In9.Cu" "In10.Cu"
			)
			(hatch none 0.5)
			(connect_pads
				(clearance 0)
			)
			(min_thickness 0.25)
			(keepout
				(tracks not_allowed)
				(vias allowed)
				(pads allowed)
				(copperpour not_allowed)
				(footprints allowed)
			)
			(placement
				(enabled no)
				(sheetname "")
			)
			(fill
				(thermal_gap 0.5)
				(thermal_bridge_width 0.5)
				(island_removal_mode 0)
			)
			(polygon
				(pts
					(arc
						(start 103.4796 -57.286652)
						(mid 101.6254 -57.286652)
						(end 103.4796 -57.286652)
					)
				)
			)
		)
		(zone
			(layers "F.Cu" "B.Cu" "In1.Cu" "In2.Cu" "In3.Cu" "In4.Cu" "In5.Cu" "In6.Cu"
				"In7.Cu" "In8.Cu" "In9.Cu" "In10.Cu"
			)
			(hatch none 0.5)
			(connect_pads
				(clearance 0)
			)
			(min_thickness 0.25)
			(keepout
				(tracks not_allowed)
				(vias allowed)
				(pads allowed)
				(copperpour not_allowed)
				(footprints allowed)
			)
			(placement
				(enabled no)
				(sheetname "")
			)
			(fill
				(thermal_gap 0.5)
				(thermal_bridge_width 0.5)
				(island_removal_mode 0)
			)
			(polygon
				(pts
					(arc
						(start 103.4796 -50.936652)
						(mid 101.6254 -50.936652)
						(end 103.4796 -50.936652)
					)
				)
			)
		)
		(zone
			(layers "F.Cu" "B.Cu" "In1.Cu" "In2.Cu" "In3.Cu" "In4.Cu" "In5.Cu" "In6.Cu"
				"In7.Cu" "In8.Cu" "In9.Cu" "In10.Cu"
			)
			(hatch none 0.5)
			(connect_pads
				(clearance 0)
			)
			(min_thickness 0.25)
			(keepout
				(tracks not_allowed)
				(vias allowed)
				(pads allowed)
				(copperpour not_allowed)
				(footprints allowed)
			)
			(placement
				(enabled no)
				(sheetname "")
			)
			(fill
				(thermal_gap 0.5)
				(thermal_bridge_width 0.5)
				(island_removal_mode 0)
			)
			(polygon
				(pts
					(arc
						(start 106.0196 -57.286652)
						(mid 104.1654 -57.286652)
						(end 106.0196 -57.286652)
					)
				)
			)
		)
		(zone
			(layers "F.Cu" "B.Cu" "In1.Cu" "In2.Cu" "In3.Cu" "In4.Cu" "In5.Cu" "In6.Cu"
				"In7.Cu" "In8.Cu" "In9.Cu" "In10.Cu"
			)
			(hatch none 0.5)
			(connect_pads
				(clearance 0)
			)
			(min_thickness 0.25)
			(keepout
				(tracks not_allowed)
				(vias allowed)
				(pads allowed)
				(copperpour not_allowed)
				(footprints allowed)
			)
			(placement
				(enabled no)
				(sheetname "")
			)
			(fill
				(thermal_gap 0.5)
				(thermal_bridge_width 0.5)
				(island_removal_mode 0)
			)
			(polygon
				(pts
					(arc
						(start 106.0196 -50.936652)
						(mid 104.1654 -50.936652)
						(end 106.0196 -50.936652)
					)
				)
			)
		)
	)
)
